(kicad_pcb
	(version 20260206)
	(generator "pcbnew")
	(generator_version "10.0")
	(general
		(thickness 1.6)
		(legacy_teardrops no)
	)
	(paper "A4")
	(title_block
		(title "pdpb — Lightning_PDPB_BRD.brd")
		(comment 1 "Lightning (Wiwynn / Facebook NVMe JBOF) / footprints 28-29 of 1140")
	)
	(layers
		(0 "F.Cu" signal "TOP")
		(4 "In1.Cu" signal "L2GND")
		(6 "In2.Cu" signal "L3")
		(8 "In3.Cu" signal "L4VCC")
		(10 "In4.Cu" signal "L5VCC")
		(12 "In5.Cu" signal "L6")
		(14 "In6.Cu" signal "L7GND")
		(2 "B.Cu" signal "BOTTOM")
		(9 "F.Adhes" user "F.Adhesive")
		(11 "B.Adhes" user "B.Adhesive")
		(13 "F.Paste" user "Package Geometry/Pastemask Top")
		(15 "B.Paste" user "Package Geometry/Pastemask Bottom")
		(5 "F.SilkS" user "Ref Des/Silkscreen Top")
		(7 "B.SilkS" user "Ref Des/Silkscreen Bottom")
		(1 "F.Mask" user "Board Geometry/Soldermask Top")
		(3 "B.Mask" user "Board Geometry/Soldermask Bottom")
		(17 "Dwgs.User" user "User.Drawings")
		(19 "Cmts.User" user "User.Comments")
		(21 "Eco1.User" user "User.Eco1")
		(23 "Eco2.User" user "User.Eco2")
		(25 "Edge.Cuts" user "Board Geometry/Outline")
		(27 "Margin" user)
		(31 "F.CrtYd" user "Package Geometry/Place Bound Top")
		(29 "B.CrtYd" user "Package Geometry/Place Bound Bottom")
		(35 "F.Fab" user "Ref Des/Assembly Top")
		(33 "B.Fab" user "Ref Des/Assembly Bottom")
	)
	(footprint ""
		(layer "F.Cu")
		(at 88.011 -436.499)
		(property "Reference" "C8894"
			(at 0 0 0)
			(layer "F.SilkS")
			(hide yes)
			(effects
				(font
					(size 1.27 1.27)
				)
			)
		)
		(property "Value" "SCD1U16V2KX-3GP"
			(at 1.1811 -2.7051 0)
			(unlocked yes)
			(layer "F.Fab")
			(hide yes)
			(effects
				(font
					(size 1.016 1.016)
					(thickness 0.1524)
				)
			)
		)
		(property "Device Type" "C402H22"
			(at 1.1811 -4.2291 0)
			(unlocked yes)
			(layer "F.Fab")
			(hide yes)
			(effects
				(font
					(size 1.016 1.016)
					(thickness 0.1524)
				)
			)
		)
		(duplicate_pad_numbers_are_jumpers no)
		(fp_rect
			(start -0.4318 0.9525)
			(end 0.4318 -0.9525)
			(stroke
				(width 0)
				(type default)
			)
			(fill no)
			(layer "F.CrtYd")
		)
		(fp_rect
			(start -0.4318 0.9525)
			(end 0.4318 -0.9525)
			(stroke
				(width 0)
				(type default)
			)
			(fill no)
			(layer "F.Fab")
		)
		(pad "1" smd custom
			(at 0 -0.4445)
			(size 0.1524 0.1524)
			(layers "F.Cu" "F.Mask" "F.Paste")
			(net "VDDA_1")
			(options
				(clearance outline)
				(anchor circle)
			)
			(primitives
				(gr_poly
					(pts
						(arc
							(start 0.3048 -0.2032)
							(mid 0.275042 -0.275042)
							(end 0.2032 -0.3048)
						)
						(arc
							(start -0.2032 -0.3048)
							(mid -0.275042 -0.275042)
							(end -0.3048 -0.2032)
						)
						(arc
							(start -0.3048 0.2032)
							(mid -0.275042 0.275042)
							(end -0.2032 0.3048)
						)
						(arc
							(start 0.2032 0.3048)
							(mid 0.275042 0.275042)
							(end 0.3048 0.2032)
						)
					)
					(width 0)
					(fill yes)
				)
			)
		)
		(pad "2" smd custom
			(at 0 0.4445)
			(size 0.1524 0.1524)
			(layers "F.Cu" "F.Mask" "F.Paste")
			(net "GND")
			(options
				(clearance outline)
				(anchor circle)
			)
			(primitives
				(gr_poly
					(pts
						(arc
							(start 0.3048 -0.2032)
							(mid 0.275042 -0.275042)
							(end 0.2032 -0.3048)
						)
						(arc
							(start -0.2032 -0.3048)
							(mid -0.275042 -0.275042)
							(end -0.3048 -0.2032)
						)
						(arc
							(start -0.3048 0.2032)
							(mid -0.275042 0.275042)
							(end -0.2032 0.3048)
						)
						(arc
							(start 0.2032 0.3048)
							(mid 0.275042 0.275042)
							(end 0.3048 0.2032)
						)
					)
					(width 0)
					(fill yes)
				)
			)
		)
	)
	(footprint ""
		(layer "F.Cu")
		(at 93.98 -210.82 90)
		(property "Reference" "EU3"
			(at 0 0 90)
			(layer "F.SilkS")
			(hide yes)
			(effects
				(font
					(size 1.27 1.27)
				)
			)
		)
		(property "Value" "9ZXL1231AKLFT-GP"
			(at -6.5278 -7.2009 90)
			(unlocked yes)
			(layer "F.Fab")
			(hide yes)
			(effects
				(font
					(size 1.016 1.016)
					(thickness 0.1524)
				)
			)
		)
		(property "Device Type" "QFN64G9-G6D25H40"
			(at -6.5278 -8.7249 90)
			(unlocked yes)
			(layer "F.Fab")
			(hide yes)
			(effects
				(font
					(size 1.016 1.016)
					(thickness 0.1524)
				)
			)
		)
		(duplicate_pad_numbers_are_jumpers no)
		(fp_line
			(start 1.7526 -5.71881)
			(end 1.7526 -5.21081)
			(stroke
				(width 0.1524)
				(type default)
			)
			(layer "F.SilkS")
		)
		(fp_line
			(start -3.2639 -5.71881)
			(end -3.2639 -5.21081)
			(stroke
				(width 0.1524)
				(type default)
			)
			(layer "F.SilkS")
		)
		(fp_line
			(start -3.9878 -5.5118)
			(end -5.5118 -5.5118)
			(stroke
				(width 0.1524)
				(type default)
			)
			(layer "F.SilkS")
		)
		(fp_line
			(start -5.5118 -5.5118)
			(end -5.5118 -3.9243)
			(stroke
				(width 0.1524)
				(type default)
			)
			(layer "F.SilkS")
		)
		(fp_line
			(start -0.74041 -5.21081)
			(end -0.74041 -5.97281)
			(stroke
				(width 0.1524)
				(type default)
			)
			(layer "F.SilkS")
		)
		(fp_line
			(start -5.97281 -2.2606)
			(end -5.21081 -2.2606)
			(stroke
				(width 0.1524)
				(type default)
			)
			(layer "F.SilkS")
		)
		(fp_line
			(start 5.21081 -1.778)
			(end 5.97281 -1.778)
			(stroke
				(width 0.1524)
				(type default)
			)
			(layer "F.SilkS")
		)
		(fp_line
			(start -5.21081 0.254)
			(end -5.71881 0.254)
			(stroke
				(width 0.1524)
				(type default)
			)
			(layer "F.SilkS")
		)
		(fp_line
			(start 5.71881 0.7112)
			(end 5.21081 0.7112)
			(stroke
				(width 0.1524)
				(type default)
			)
			(layer "F.SilkS")
		)
		(fp_line
			(start -5.97281 2.7432)
			(end -5.21081 2.7432)
			(stroke
				(width 0.1524)
				(type default)
			)
			(layer "F.SilkS")
		)
		(fp_line
			(start 5.21081 3.22961)
			(end 5.97281 3.22961)
			(stroke
				(width 0.1524)
				(type default)
			)
			(layer "F.SilkS")
		)
		(fp_line
			(start -5.4991 4.1148)
			(end -5.4991 5.5118)
			(stroke
				(width 0.1524)
				(type default)
			)
			(layer "F.SilkS")
		)
		(fp_line
			(start 2.2352 5.21081)
			(end 2.2352 5.71881)
			(stroke
				(width 0.1524)
				(type default)
			)
			(layer "F.SilkS")
		)
		(fp_line
			(start -2.7432 5.21081)
			(end -2.7432 5.71881)
			(stroke
				(width 0.1524)
				(type default)
			)
			(layer "F.SilkS")
		)
		(fp_line
			(start 5.5118 5.4991)
			(end 5.5118 3.9878)
			(stroke
				(width 0.1524)
				(type default)
			)
			(layer "F.SilkS")
		)
		(fp_line
			(start 4.0767 5.4991)
			(end 5.5118 5.4991)
			(stroke
				(width 0.1524)
				(type default)
			)
			(layer "F.SilkS")
		)
		(fp_line
			(start -5.4991 5.5118)
			(end -4.2037 5.5118)
			(stroke
				(width 0.1524)
				(type default)
			)
			(layer "F.SilkS")
		)
		(fp_line
			(start -0.7366 5.97281)
			(end -0.7366 5.21081)
			(stroke
				(width 0.1524)
				(type default)
			)
			(layer "F.SilkS")
		)
		(fp_poly
			(pts
				(xy 5.5118 -4.05511) (xy 4.05511 -5.5118) (xy 5.5118 -5.5118)
			)
			(stroke
				(width 0)
				(type default)
			)
			(fill yes)
			(layer "F.SilkS")
		)
		(fp_rect
			(start -4.4958 4.4958)
			(end 4.4958 -4.4958)
			(stroke
				(width 0)
				(type default)
			)
			(fill no)
			(layer "F.CrtYd")
		)
		(fp_poly
			(pts
				(xy -5.5118 5.5118) (xy -5.5118 -5.5118) (xy 5.5118 -5.5118) (xy 5.5118 -0.5461) (xy 4.4958 -0.5461)
				(xy 4.4958 -4.4958) (xy -4.4958 -4.4958) (xy -4.4958 4.4958) (xy 4.4958 4.4958) (xy 4.4958 -0.5334)
				(xy 5.5118 -0.5334) (xy 5.5118 5.5118)
			)
			(stroke
				(width 0)
				(type default)
			)
			(fill no)
			(layer "F.CrtYd")
		)
		(fp_rect
			(start -5.5118 5.5118)
			(end 5.5118 -5.5118)
			(stroke
				(width 0)
				(type default)
			)
			(fill no)
			(layer "F.Fab")
		)
		(pad "1" smd rect
			(at 3.75031 -4.550918 90)
			(size 0.3048 0.9144)
			(layers "F.Cu" "F.Mask" "F.Paste")
			(net "VDDA_3")
		)
		(pad "2" smd rect
			(at 3.24993 -4.42341 90)
			(size 0.3048 1.1684)
			(layers "F.Cu" "F.Mask" "F.Paste")
			(net "GND")
		)
		(pad "3" smd rect
			(at 2.74955 -4.42341 90)
			(size 0.3048 1.1684)
			(layers "F.Cu" "F.Mask" "F.Paste")
			(net "Net_1326")
		)
		(pad "4" smd rect
			(at 2.25044 -4.42341 90)
			(size 0.3048 1.1684)
			(layers "F.Cu" "F.Mask" "F.Paste")
			(net "CLK_BUF_EU3_100M_133M#")
		)
		(pad "5" smd rect
			(at 1.75006 -4.42341 90)
			(size 0.3048 1.1684)
			(layers "F.Cu" "F.Mask" "F.Paste")
			(net "CLK_BUF_EU3_HIBW_BYPM_LOBW#")
		)
		(pad "6" smd rect
			(at 1.24968 -4.42341 90)
			(size 0.3048 1.1684)
			(layers "F.Cu" "F.Mask" "F.Paste")
			(net "P3V3_PG")
		)
		(pad "7" smd rect
			(at 0.75057 -4.42341 90)
			(size 0.3048 1.1684)
			(layers "F.Cu" "F.Mask" "F.Paste")
			(net "GND")
		)
		(pad "8" smd rect
			(at 0.25019 -4.42341 90)
			(size 0.3048 1.1684)
			(layers "F.Cu" "F.Mask" "F.Paste")
			(net "VDDR_3")
		)
		(pad "9" smd rect
			(at -0.25019 -4.42341 90)
			(size 0.3048 1.1684)
			(layers "F.Cu" "F.Mask" "F.Paste")
			(net "PE_100M_CLK2_P")
		)
		(pad "10" smd rect
			(at -0.75057 -4.42341 90)
			(size 0.3048 1.1684)
			(layers "F.Cu" "F.Mask" "F.Paste")
			(net "PE_100M_CLK2_N")
		)
		(pad "11" smd rect
			(at -1.24968 -4.42341 90)
			(size 0.3048 1.1684)
			(layers "F.Cu" "F.Mask" "F.Paste")
			(net "CLK_BUF_EU3_SMB_A0_TRI")
		)
		(pad "12" smd rect
			(at -1.75006 -4.42341 90)
			(size 0.3048 1.1684)
			(layers "F.Cu" "F.Mask" "F.Paste")
			(net "I2C_SDA_BUF_8_EU3_R")
		)
		(pad "13" smd rect
			(at -2.25044 -4.42341 90)
			(size 0.3048 1.1684)
			(layers "F.Cu" "F.Mask" "F.Paste")
			(net "I2C_SCL_BUF_8_EU3_R")
		)
		(pad "14" smd rect
			(at -2.74955 -4.42341 90)
			(size 0.3048 1.1684)
			(layers "F.Cu" "F.Mask" "F.Paste")
			(net "CLK_BUF_EU3_SMB_A1_TRI")
		)
		(pad "15" smd rect
			(at -3.24993 -4.42341 90)
			(size 0.3048 1.1684)
			(layers "F.Cu" "F.Mask" "F.Paste")
			(net "Net_1328")
		)
		(pad "16" smd rect
			(at -3.75031 -4.550918 90)
			(size 0.3048 0.9144)
			(layers "F.Cu" "F.Mask" "F.Paste")
			(net "Net_1327")
		)
		(pad "17" smd rect
			(at -4.550918 -3.75031 90)
			(size 0.9144 0.3048)
			(layers "F.Cu" "F.Mask" "F.Paste")
			(net "Net_331")
		)
		(pad "18" smd rect
			(at -4.42341 -3.24993 90)
			(size 1.1684 0.3048)
			(layers "F.Cu" "F.Mask" "F.Paste")
			(net "Net_330")
		)
		(pad "19" smd rect
			(at -4.42341 -2.74955 90)
			(size 1.1684 0.3048)
			(layers "F.Cu" "F.Mask" "F.Paste")
			(net "CLK_BUFFER_EU3_VOE_N")
		)
		(pad "20" smd rect
			(at -4.42341 -2.25044 90)
			(size 1.1684 0.3048)
			(layers "F.Cu" "F.Mask" "F.Paste")
			(net "CLK_BUFFER_EU3_VOE_N")
		)
		(pad "21" smd rect
			(at -4.42341 -1.75006 90)
			(size 1.1684 0.3048)
			(layers "F.Cu" "F.Mask" "F.Paste")
			(net "Net_329")
		)
		(pad "22" smd rect
			(at -4.42341 -1.24968 90)
			(size 1.1684 0.3048)
			(layers "F.Cu" "F.Mask" "F.Paste")
			(net "Net_328")
		)
		(pad "23" smd rect
			(at -4.42341 -0.75057 90)
			(size 1.1684 0.3048)
			(layers "F.Cu" "F.Mask" "F.Paste")
			(net "GND")
		)
		(pad "24" smd rect
			(at -4.42341 -0.25019 90)
			(size 1.1684 0.3048)
			(layers "F.Cu" "F.Mask" "F.Paste")
			(net "VDD_DIFF_3")
		)
		(pad "25" smd rect
			(at -4.42341 0.25019 90)
			(size 1.1684 0.3048)
			(layers "F.Cu" "F.Mask" "F.Paste")
			(net "VDD_IO_3")
		)
		(pad "26" smd rect
			(at -4.42341 0.75057 90)
			(size 1.1684 0.3048)
			(layers "F.Cu" "F.Mask" "F.Paste")
			(net "PE_CLK_100M_DR4_2_R_P")
		)
		(pad "27" smd rect
			(at -4.42341 1.24968 90)
			(size 1.1684 0.3048)
			(layers "F.Cu" "F.Mask" "F.Paste")
			(net "PE_CLK_100M_DR4_2_R_N")
		)
		(pad "28" smd rect
			(at -4.42341 1.75006 90)
			(size 1.1684 0.3048)
			(layers "F.Cu" "F.Mask" "F.Paste")
			(net "SSD_PRSNT4")
		)
		(pad "29" smd rect
			(at -4.42341 2.25044 90)
			(size 1.1684 0.3048)
			(layers "F.Cu" "F.Mask" "F.Paste")
			(net "SSD4_CLK0_OE_R_N")
		)
		(pad "30" smd rect
			(at -4.42341 2.74955 90)
			(size 1.1684 0.3048)
			(layers "F.Cu" "F.Mask" "F.Paste")
			(net "PE_CLK_100M_DR4_1_R_P")
		)
		(pad "31" smd rect
			(at -4.42341 3.24993 90)
			(size 1.1684 0.3048)
			(layers "F.Cu" "F.Mask" "F.Paste")
			(net "PE_CLK_100M_DR4_1_R_N")
		)
		(pad "32" smd rect
			(at -4.550918 3.75031 90)
			(size 0.9144 0.3048)
			(layers "F.Cu" "F.Mask" "F.Paste")
			(net "VDD_IO_3")
		)
		(pad "33" smd rect
			(at -3.75031 4.550918 90)
			(size 0.3048 0.9144)
			(layers "F.Cu" "F.Mask" "F.Paste")
			(net "GND")
		)
		(pad "34" smd rect
			(at -3.24993 4.42341 90)
			(size 0.3048 1.1684)
			(layers "F.Cu" "F.Mask" "F.Paste")
			(net "PE_CLK_100M_DR3_2_R_P")
		)
		(pad "35" smd rect
			(at -2.74955 4.42341 90)
			(size 0.3048 1.1684)
			(layers "F.Cu" "F.Mask" "F.Paste")
			(net "PE_CLK_100M_DR3_2_R_N")
		)
		(pad "36" smd rect
			(at -2.25044 4.42341 90)
			(size 0.3048 1.1684)
			(layers "F.Cu" "F.Mask" "F.Paste")
			(net "SSD_PRSNT3")
		)
		(pad "37" smd rect
			(at -1.75006 4.42341 90)
			(size 0.3048 1.1684)
			(layers "F.Cu" "F.Mask" "F.Paste")
			(net "SSD3_CLK0_OE_R_N")
		)
		(pad "38" smd rect
			(at -1.24968 4.42341 90)
			(size 0.3048 1.1684)
			(layers "F.Cu" "F.Mask" "F.Paste")
			(net "PE_CLK_100M_DR3_1_R_P")
		)
		(pad "39" smd rect
			(at -0.75057 4.42341 90)
			(size 0.3048 1.1684)
			(layers "F.Cu" "F.Mask" "F.Paste")
			(net "PE_CLK_100M_DR3_1_R_N")
		)
		(pad "40" smd rect
			(at -0.25019 4.42341 90)
			(size 0.3048 1.1684)
			(layers "F.Cu" "F.Mask" "F.Paste")
			(net "VDD_DIFF_3")
		)
		(pad "41" smd rect
			(at 0.25019 4.42341 90)
			(size 0.3048 1.1684)
			(layers "F.Cu" "F.Mask" "F.Paste")
			(net "GND")
		)
		(pad "42" smd rect
			(at 0.75057 4.42341 90)
			(size 0.3048 1.1684)
			(layers "F.Cu" "F.Mask" "F.Paste")
			(net "Net_309")
		)
		(pad "43" smd rect
			(at 1.24968 4.42341 90)
			(size 0.3048 1.1684)
			(layers "F.Cu" "F.Mask" "F.Paste")
			(net "Net_308")
		)
		(pad "44" smd rect
			(at 1.75006 4.42341 90)
			(size 0.3048 1.1684)
			(layers "F.Cu" "F.Mask" "F.Paste")
			(net "CLK_BUFFER_EU3_VOE_N")
		)
		(pad "45" smd rect
			(at 2.25044 4.42341 90)
			(size 0.3048 1.1684)
			(layers "F.Cu" "F.Mask" "F.Paste")
			(net "CLK_BUFFER_EU3_VOE_N")
		)
		(pad "46" smd rect
			(at 2.74955 4.42341 90)
			(size 0.3048 1.1684)
			(layers "F.Cu" "F.Mask" "F.Paste")
			(net "Net_311")
		)
		(pad "47" smd rect
			(at 3.24993 4.42341 90)
			(size 0.3048 1.1684)
			(layers "F.Cu" "F.Mask" "F.Paste")
			(net "Net_310")
		)
		(pad "48" smd rect
			(at 3.75031 4.550918 90)
			(size 0.3048 0.9144)
			(layers "F.Cu" "F.Mask" "F.Paste")
			(net "GND")
		)
		(pad "49" smd rect
			(at 4.550918 3.75031 90)
			(size 0.9144 0.3048)
			(layers "F.Cu" "F.Mask" "F.Paste")
			(net "VDD_IO_3")
		)
		(pad "50" smd rect
			(at 4.42341 3.24993 90)
			(size 1.1684 0.3048)
			(layers "F.Cu" "F.Mask" "F.Paste")
			(net "PE_CLK_100M_DR7_2_R_P")
		)
		(pad "51" smd rect
			(at 4.42341 2.74955 90)
			(size 1.1684 0.3048)
			(layers "F.Cu" "F.Mask" "F.Paste")
			(net "PE_CLK_100M_DR7_2_R_N")
		)
		(pad "52" smd rect
			(at 4.42341 2.25044 90)
			(size 1.1684 0.3048)
			(layers "F.Cu" "F.Mask" "F.Paste")
			(net "SSD_PRSNT7")
		)
		(pad "53" smd rect
			(at 4.42341 1.75006 90)
			(size 1.1684 0.3048)
			(layers "F.Cu" "F.Mask" "F.Paste")
			(net "SSD7_CLK0_OE_R_N")
		)
		(pad "54" smd rect
			(at 4.42341 1.24968 90)
			(size 1.1684 0.3048)
			(layers "F.Cu" "F.Mask" "F.Paste")
			(net "PE_CLK_100M_DR7_1_R_P")
		)
		(pad "55" smd rect
			(at 4.42341 0.75057 90)
			(size 1.1684 0.3048)
			(layers "F.Cu" "F.Mask" "F.Paste")
			(net "PE_CLK_100M_DR7_1_R_N")
		)
		(pad "56" smd rect
			(at 4.42341 0.25019 90)
			(size 1.1684 0.3048)
			(layers "F.Cu" "F.Mask" "F.Paste")
			(net "VDD_IO_3")
		)
		(pad "57" smd rect
			(at 4.42341 -0.25019 90)
			(size 1.1684 0.3048)
			(layers "F.Cu" "F.Mask" "F.Paste")
			(net "VDD_DIFF_3")
		)
		(pad "58" smd rect
			(at 4.42341 -0.75057 90)
			(size 1.1684 0.3048)
			(layers "F.Cu" "F.Mask" "F.Paste")
			(net "GND")
		)
		(pad "59" smd rect
			(at 4.42341 -1.24968 90)
			(size 1.1684 0.3048)
			(layers "F.Cu" "F.Mask" "F.Paste")
			(net "PE_CLK_100M_DR12_2_R_P")
		)
		(pad "60" smd rect
			(at 4.42341 -1.75006 90)
			(size 1.1684 0.3048)
			(layers "F.Cu" "F.Mask" "F.Paste")
			(net "PE_CLK_100M_DR12_2_R_N")
		)
		(pad "61" smd rect
			(at 4.42341 -2.25044 90)
			(size 1.1684 0.3048)
			(layers "F.Cu" "F.Mask" "F.Paste")
			(net "SSD_PRSNT12")
		)
		(pad "62" smd rect
			(at 4.42341 -2.74955 90)
			(size 1.1684 0.3048)
			(layers "F.Cu" "F.Mask" "F.Paste")
			(net "SSD12_CLK0_OE_R_N")
		)
		(pad "63" smd rect
			(at 4.42341 -3.24993 90)
			(size 1.1684 0.3048)
			(layers "F.Cu" "F.Mask" "F.Paste")
			(net "PE_CLK_100M_DR12_1_R_P")
		)
		(pad "64" smd rect
			(at 4.550918 -3.75031 90)
			(size 0.9144 0.3048)
			(layers "F.Cu" "F.Mask" "F.Paste")
			(net "PE_CLK_100M_DR12_1_R_N")
		)
		(pad "65" smd rect
			(at 0 0 90)
			(size 6.2484 6.2484)
			(layers "F.Cu" "F.Mask" "F.Paste")
			(net "GND")
		)
	)
)
